# S9S_MB_2U (Grand Teton) — schematic netlist excerpt (pin names and nets, part order shuffled) for the footprints in the layout excerpt that follows; sources: Cadence DE-HDL packaged netlist, KiCad conversion of 03242023_DA0F0TMBIJ0_F0T_Motherboard_J_brd_V01_OCP.brd

R1345  Q_RES  0 5% CHIP  pkg 0402LF  page 239 : A = JTAG_BMC_DBP_TDI_R ; B = JTAG_BMC_DBP_TDI
C246  Q_CAP  10UF 6.3V 20% X6S  pkg C0402  page 77 : A = PVCCIN_CPU1 ; B = GND

(kicad_pcb
	(version 20260206)
	(generator "pcbnew")
	(generator_version "10.0")
	(general
		(thickness 1.6)
		(legacy_teardrops no)
	)
	(paper "A4")
	(title_block
		(title "03242023_DA0F0TMBIJ0_F0T_Motherboard_J_brd_V01_OCP.brd")
		(comment 1 "Grand Teton / footprints 694-695 of 6105")
	)
	(layers
		(0 "F.Cu" signal "TOP")
		(4 "In1.Cu" signal "GND")
		(6 "In2.Cu" signal "IN1")
		(8 "In3.Cu" signal "GND1")
		(10 "In4.Cu" signal "IN2")
		(12 "In5.Cu" signal "GND2")
		(14 "In6.Cu" signal "IN3")
		(16 "In7.Cu" signal "GND3")
		(18 "In8.Cu" signal "VCC")
		(20 "In9.Cu" signal "VCC1")
		(22 "In10.Cu" signal "GND4")
		(24 "In11.Cu" signal "IN4")
		(26 "In12.Cu" signal "GND5")
		(28 "In13.Cu" signal "IN5")
		(30 "In14.Cu" signal "GND6")
		(32 "In15.Cu" signal "IN6")
		(34 "In16.Cu" signal "GND7")
		(2 "B.Cu" signal "BOTTOM")
		(9 "F.Adhes" user "F.Adhesive")
		(11 "B.Adhes" user "B.Adhesive")
		(13 "F.Paste" user "Package Geometry/Pastemask Top")
		(15 "B.Paste" user "Package Geometry/Pastemask Bottom")
		(5 "F.SilkS" user "Ref Des/Silkscreen Top")
		(7 "B.SilkS" user "Ref Des/Silkscreen Bottom")
		(1 "F.Mask" user "Board Geometry/Soldermask Top")
		(3 "B.Mask" user "Board Geometry/Soldermask Bottom")
		(17 "Dwgs.User" user "User.Drawings")
		(19 "Cmts.User" user "User.Comments")
		(21 "Eco1.User" user "User.Eco1")
		(23 "Eco2.User" user "User.Eco2")
		(25 "Edge.Cuts" user "Board Geometry/Outline")
		(27 "Margin" user)
		(31 "F.CrtYd" user "Package Geometry/Place Bound Top")
		(29 "B.CrtYd" user "Package Geometry/Place Bound Bottom")
		(35 "F.Fab" user "Ref Des/Assembly Top")
		(33 "B.Fab" user "Ref Des/Assembly Bottom")
	)
	(footprint ""
		(layer "F.Cu")
		(at 105.2957 -255.0541 90)
		(property "Reference" "C246"
			(at 0 0 90)
			(layer "F.SilkS")
			(hide yes)
			(effects
				(font
					(size 1.27 1.27)
				)
			)
		)
		(property "Value" ""
			(at 0 0 90)
			(layer "F.Fab")
			(effects
				(font
					(size 1.27 1.27)
				)
			)
		)
		(duplicate_pad_numbers_are_jumpers no)
		(fp_line
			(start 0.7874 -0.4064)
			(end 0.7874 0.4064)
			(stroke
				(width 0.1524)
				(type default)
			)
			(layer "F.SilkS")
		)
		(fp_line
			(start -0.7874 -0.4064)
			(end 0.7874 -0.4064)
			(stroke
				(width 0.1524)
				(type default)
			)
			(layer "F.SilkS")
		)
		(fp_line
			(start 0.7874 0.4064)
			(end -0.7874 0.4064)
			(stroke
				(width 0.1524)
				(type default)
			)
			(layer "F.SilkS")
		)
		(fp_line
			(start -0.7874 0.4064)
			(end -0.7874 -0.4064)
			(stroke
				(width 0.1524)
				(type default)
			)
			(layer "F.SilkS")
		)
		(fp_line
			(start -0.12065 -0.305054)
			(end -0.12065 -0.2794)
			(stroke
				(width 0.1)
				(type default)
			)
			(layer "F.Fab")
		)
		(fp_line
			(start -0.67945 -0.305054)
			(end -0.12065 -0.305054)
			(stroke
				(width 0.1)
				(type default)
			)
			(layer "F.Fab")
		)
		(fp_line
			(start 0.67945 -0.3048)
			(end 0.67945 0.3048)
			(stroke
				(width 0.1)
				(type default)
			)
			(layer "F.Fab")
		)
		(fp_line
			(start 0.12065 -0.3048)
			(end 0.67945 -0.3048)
			(stroke
				(width 0.1)
				(type default)
			)
			(layer "F.Fab")
		)
		(fp_line
			(start 0.12065 -0.2794)
			(end 0.12065 -0.3048)
			(stroke
				(width 0.1)
				(type default)
			)
			(layer "F.Fab")
		)
		(fp_line
			(start -0.12065 -0.2794)
			(end 0.12065 -0.2794)
			(stroke
				(width 0.1)
				(type default)
			)
			(layer "F.Fab")
		)
		(fp_line
			(start 0.120396 0.2794)
			(end -0.12065 0.2794)
			(stroke
				(width 0.1)
				(type default)
			)
			(layer "F.Fab")
		)
		(fp_line
			(start -0.12065 0.2794)
			(end -0.12065 0.3048)
			(stroke
				(width 0.1)
				(type default)
			)
			(layer "F.Fab")
		)
		(fp_line
			(start 0.67945 0.3048)
			(end 0.120396 0.3048)
			(stroke
				(width 0.1)
				(type default)
			)
			(layer "F.Fab")
		)
		(fp_line
			(start 0.120396 0.3048)
			(end 0.120396 0.2794)
			(stroke
				(width 0.1)
				(type default)
			)
			(layer "F.Fab")
		)
		(fp_line
			(start -0.12065 0.3048)
			(end -0.67945 0.3048)
			(stroke
				(width 0.1)
				(type default)
			)
			(layer "F.Fab")
		)
		(fp_line
			(start -0.67945 0.3048)
			(end -0.67945 -0.305054)
			(stroke
				(width 0.1)
				(type default)
			)
			(layer "F.Fab")
		)
		(pad "1" smd circle
			(at -0.40005 0 90)
			(size 0 0)
			(layers "F.Cu" "F.Mask" "F.Paste")
			(net "PVCCIN_CPU1")
		)
		(pad "2" smd circle
			(at 0.40005 0 90)
			(size 0 0)
			(layers "F.Cu" "F.Mask" "F.Paste")
			(net "GND")
		)
	)
	(footprint ""
		(layer "F.Cu")
		(at 128.9685 -74.824082 -90)
		(property "Reference" "R1345"
			(at 0 0 270)
			(layer "F.SilkS")
			(hide yes)
			(effects
				(font
					(size 1.27 1.27)
				)
			)
		)
		(property "Value" ""
			(at 0 0 270)
			(layer "F.Fab")
			(effects
				(font
					(size 1.27 1.27)
				)
			)
		)
		(duplicate_pad_numbers_are_jumpers no)
		(fp_line
			(start -0.7874 0.4064)
			(end -0.7874 -0.4064)
			(stroke
				(width 0.1524)
				(type default)
			)
			(layer "F.SilkS")
		)
		(fp_line
			(start 0.7874 0.4064)
			(end -0.7874 0.4064)
			(stroke
				(width 0.1524)
				(type default)
			)
			(layer "F.SilkS")
		)
		(fp_line
			(start -0.7874 -0.4064)
			(end 0.7874 -0.4064)
			(stroke
				(width 0.1524)
				(type default)
			)
			(layer "F.SilkS")
		)
		(fp_line
			(start 0.7874 -0.4064)
			(end 0.7874 0.4064)
			(stroke
				(width 0.1524)
				(type default)
			)
			(layer "F.SilkS")
		)
		(fp_line
			(start -0.67945 0.3048)
			(end -0.67945 -0.305054)
			(stroke
				(width 0.1)
				(type default)
			)
			(layer "F.Fab")
		)
		(fp_line
			(start -0.12065 0.3048)
			(end -0.67945 0.3048)
			(stroke
				(width 0.1)
				(type default)
			)
			(layer "F.Fab")
		)
		(fp_line
			(start 0.120396 0.3048)
			(end 0.120396 0.2794)
			(stroke
				(width 0.1)
				(type default)
			)
			(layer "F.Fab")
		)
		(fp_line
			(start 0.67945 0.3048)
			(end 0.120396 0.3048)
			(stroke
				(width 0.1)
				(type default)
			)
			(layer "F.Fab")
		)
		(fp_line
			(start -0.12065 0.2794)
			(end -0.12065 0.3048)
			(stroke
				(width 0.1)
				(type default)
			)
			(layer "F.Fab")
		)
		(fp_line
			(start 0.120396 0.2794)
			(end -0.12065 0.2794)
			(stroke
				(width 0.1)
				(type default)
			)
			(layer "F.Fab")
		)
		(fp_line
			(start -0.12065 -0.2794)
			(end 0.12065 -0.2794)
			(stroke
				(width 0.1)
				(type default)
			)
			(layer "F.Fab")
		)
		(fp_line
			(start 0.12065 -0.2794)
			(end 0.12065 -0.3048)
			(stroke
				(width 0.1)
				(type default)
			)
			(layer "F.Fab")
		)
		(fp_line
			(start 0.12065 -0.3048)
			(end 0.67945 -0.3048)
			(stroke
				(width 0.1)
				(type default)
			)
			(layer "F.Fab")
		)
		(fp_line
			(start 0.67945 -0.3048)
			(end 0.67945 0.3048)
			(stroke
				(width 0.1)
				(type default)
			)
			(layer "F.Fab")
		)
		(fp_line
			(start -0.67945 -0.305054)
			(end -0.12065 -0.305054)
			(stroke
				(width 0.1)
				(type default)
			)
			(layer "F.Fab")
		)
		(fp_line
			(start -0.12065 -0.305054)
			(end -0.12065 -0.2794)
			(stroke
				(width 0.1)
				(type default)
			)
			(layer "F.Fab")
		)
		(pad "1" smd circle
			(at -0.40005 0 270)
			(size 0 0)
			(layers "F.Cu" "F.Mask" "F.Paste")
			(net "JTAG_BMC_DBP_TDI_R")
		)
		(pad "2" smd circle
			(at 0.40005 0 270)
			(size 0 0)
			(layers "F.Cu" "F.Mask" "F.Paste")
			(net "JTAG_BMC_DBP_TDI")
		)
	)
)
